# T6G (Grand Teton) — schematic netlist excerpt (pin names and nets, part order shuffled) for the footprints in the layout excerpt that follows; sources: Cadence DE-HDL packaged netlist, KiCad conversion of 04192023_DAF0TMB3IC0_F0TG_MB_C_brd_V02_OCP.brd

C8011  Q_CAP  0.1UF 25V 10% EMPTY  pkg 0402  page 240 : A = FM_AC_PWR_BTN_PDB_N ; B = GND
R1169  Q_RES  0 5% CHIP  pkg 0402LF  page 142 : A = OCP_V3_2_P3V3_PWRGD ; B = OCP_V3_2_P3V3_R2_PWRGD

(kicad_pcb
	(version 20260206)
	(generator "pcbnew")
	(generator_version "10.0")
	(general
		(thickness 1.6)
		(legacy_teardrops no)
	)
	(paper "A4")
	(title_block
		(title "04192023_DAF0TMB3IC0_F0TG_MB_C_brd_V02_OCP.brd")
		(comment 1 "Grand Teton / footprints 2610-2612 of 8354")
	)
	(layers
		(0 "F.Cu" signal "TOP")
		(4 "In1.Cu" signal "GND")
		(6 "In2.Cu" signal "IN1")
		(8 "In3.Cu" signal "GND1")
		(10 "In4.Cu" signal "IN2")
		(12 "In5.Cu" signal "GND2")
		(14 "In6.Cu" signal "IN3")
		(16 "In7.Cu" signal "GND3")
		(18 "In8.Cu" signal "VCC")
		(20 "In9.Cu" signal "VCC1")
		(22 "In10.Cu" signal "GND4")
		(24 "In11.Cu" signal "IN4")
		(26 "In12.Cu" signal "GND5")
		(28 "In13.Cu" signal "IN5")
		(30 "In14.Cu" signal "GND6")
		(32 "In15.Cu" signal "IN6")
		(34 "In16.Cu" signal "GND7")
		(2 "B.Cu" signal "BOTTOM")
		(9 "F.Adhes" user "F.Adhesive")
		(11 "B.Adhes" user "B.Adhesive")
		(13 "F.Paste" user "Package Geometry/Pastemask Top")
		(15 "B.Paste" user "Package Geometry/Pastemask Bottom")
		(5 "F.SilkS" user "Ref Des/Silkscreen Top")
		(7 "B.SilkS" user "Ref Des/Silkscreen Bottom")
		(1 "F.Mask" user "Board Geometry/Soldermask Top")
		(3 "B.Mask" user "Board Geometry/Soldermask Bottom")
		(17 "Dwgs.User" user "User.Drawings")
		(19 "Cmts.User" user "User.Comments")
		(21 "Eco1.User" user "User.Eco1")
		(23 "Eco2.User" user "User.Eco2")
		(25 "Edge.Cuts" user "Board Geometry/Outline")
		(27 "Margin" user)
		(31 "F.CrtYd" user "Package Geometry/Place Bound Top")
		(29 "B.CrtYd" user "Package Geometry/Place Bound Bottom")
		(35 "F.Fab" user "Ref Des/Assembly Top")
		(33 "B.Fab" user "Ref Des/Assembly Bottom")
	)
	(footprint ""
		(layer "F.Cu")
		(at 79.908908 -69.238114 90)
		(property "Reference" "R1169"
			(at 0 0 90)
			(layer "F.SilkS")
			(hide yes)
			(effects
				(font
					(size 1.27 1.27)
				)
			)
		)
		(property "Value" ""
			(at 0 0 90)
			(layer "F.Fab")
			(effects
				(font
					(size 1.27 1.27)
				)
			)
		)
		(duplicate_pad_numbers_are_jumpers no)
		(fp_line
			(start 0.7874 -0.4064)
			(end 0.7874 0.4064)
			(stroke
				(width 0.1524)
				(type default)
			)
			(layer "F.SilkS")
		)
		(fp_line
			(start -0.7874 -0.4064)
			(end 0.7874 -0.4064)
			(stroke
				(width 0.1524)
				(type default)
			)
			(layer "F.SilkS")
		)
		(fp_line
			(start 0.7874 0.4064)
			(end -0.7874 0.4064)
			(stroke
				(width 0.1524)
				(type default)
			)
			(layer "F.SilkS")
		)
		(fp_line
			(start -0.7874 0.4064)
			(end -0.7874 -0.4064)
			(stroke
				(width 0.1524)
				(type default)
			)
			(layer "F.SilkS")
		)
		(fp_line
			(start -0.12065 -0.305054)
			(end -0.12065 -0.2794)
			(stroke
				(width 0.1)
				(type default)
			)
			(layer "F.Fab")
		)
		(fp_line
			(start -0.67945 -0.305054)
			(end -0.12065 -0.305054)
			(stroke
				(width 0.1)
				(type default)
			)
			(layer "F.Fab")
		)
		(fp_line
			(start 0.67945 -0.3048)
			(end 0.67945 0.3048)
			(stroke
				(width 0.1)
				(type default)
			)
			(layer "F.Fab")
		)
		(fp_line
			(start 0.12065 -0.3048)
			(end 0.67945 -0.3048)
			(stroke
				(width 0.1)
				(type default)
			)
			(layer "F.Fab")
		)
		(fp_line
			(start 0.12065 -0.2794)
			(end 0.12065 -0.3048)
			(stroke
				(width 0.1)
				(type default)
			)
			(layer "F.Fab")
		)
		(fp_line
			(start -0.12065 -0.2794)
			(end 0.12065 -0.2794)
			(stroke
				(width 0.1)
				(type default)
			)
			(layer "F.Fab")
		)
		(fp_line
			(start 0.120396 0.2794)
			(end -0.12065 0.2794)
			(stroke
				(width 0.1)
				(type default)
			)
			(layer "F.Fab")
		)
		(fp_line
			(start -0.12065 0.2794)
			(end -0.12065 0.3048)
			(stroke
				(width 0.1)
				(type default)
			)
			(layer "F.Fab")
		)
		(fp_line
			(start 0.67945 0.3048)
			(end 0.120396 0.3048)
			(stroke
				(width 0.1)
				(type default)
			)
			(layer "F.Fab")
		)
		(fp_line
			(start 0.120396 0.3048)
			(end 0.120396 0.2794)
			(stroke
				(width 0.1)
				(type default)
			)
			(layer "F.Fab")
		)
		(fp_line
			(start -0.12065 0.3048)
			(end -0.67945 0.3048)
			(stroke
				(width 0.1)
				(type default)
			)
			(layer "F.Fab")
		)
		(fp_line
			(start -0.67945 0.3048)
			(end -0.67945 -0.305054)
			(stroke
				(width 0.1)
				(type default)
			)
			(layer "F.Fab")
		)
		(pad "1" smd circle
			(at -0.40005 0 90)
			(size 0 0)
			(layers "F.Cu" "F.Mask" "F.Paste")
			(net "OCP_V3_2_P3V3_PWRGD")
		)
		(pad "2" smd circle
			(at 0.40005 0 90)
			(size 0 0)
			(layers "F.Cu" "F.Mask" "F.Paste")
			(net "OCP_V3_2_P3V3_R2_PWRGD")
		)
	)
	(footprint ""
		(layer "F.Cu")
		(at 194.914774 -424.622214 90)
		(property "Reference" "C8011"
			(at 0 0 90)
			(layer "F.SilkS")
			(hide yes)
			(effects
				(font
					(size 1.27 1.27)
				)
			)
		)
		(property "Value" ""
			(at 0 0 90)
			(layer "F.Fab")
			(effects
				(font
					(size 1.27 1.27)
				)
			)
		)
		(duplicate_pad_numbers_are_jumpers no)
		(fp_line
			(start 0.7874 -0.4064)
			(end 0.7874 0.4064)
			(stroke
				(width 0.1524)
				(type default)
			)
			(layer "F.SilkS")
		)
		(fp_line
			(start -0.7874 -0.4064)
			(end 0.7874 -0.4064)
			(stroke
				(width 0.1524)
				(type default)
			)
			(layer "F.SilkS")
		)
		(fp_line
			(start 0.7874 0.4064)
			(end -0.7874 0.4064)
			(stroke
				(width 0.1524)
				(type default)
			)
			(layer "F.SilkS")
		)
		(fp_line
			(start -0.7874 0.4064)
			(end -0.7874 -0.4064)
			(stroke
				(width 0.1524)
				(type default)
			)
			(layer "F.SilkS")
		)
		(fp_line
			(start -0.12065 -0.305054)
			(end -0.12065 -0.2794)
			(stroke
				(width 0.1)
				(type default)
			)
			(layer "F.Fab")
		)
		(fp_line
			(start -0.67945 -0.305054)
			(end -0.12065 -0.305054)
			(stroke
				(width 0.1)
				(type default)
			)
			(layer "F.Fab")
		)
		(fp_line
			(start 0.67945 -0.3048)
			(end 0.67945 0.3048)
			(stroke
				(width 0.1)
				(type default)
			)
			(layer "F.Fab")
		)
		(fp_line
			(start 0.12065 -0.3048)
			(end 0.67945 -0.3048)
			(stroke
				(width 0.1)
				(type default)
			)
			(layer "F.Fab")
		)
		(fp_line
			(start 0.12065 -0.2794)
			(end 0.12065 -0.3048)
			(stroke
				(width 0.1)
				(type default)
			)
			(layer "F.Fab")
		)
		(fp_line
			(start -0.12065 -0.2794)
			(end 0.12065 -0.2794)
			(stroke
				(width 0.1)
				(type default)
			)
			(layer "F.Fab")
		)
		(fp_line
			(start 0.120396 0.2794)
			(end -0.12065 0.2794)
			(stroke
				(width 0.1)
				(type default)
			)
			(layer "F.Fab")
		)
		(fp_line
			(start -0.12065 0.2794)
			(end -0.12065 0.3048)
			(stroke
				(width 0.1)
				(type default)
			)
			(layer "F.Fab")
		)
		(fp_line
			(start 0.67945 0.3048)
			(end 0.120396 0.3048)
			(stroke
				(width 0.1)
				(type default)
			)
			(layer "F.Fab")
		)
		(fp_line
			(start 0.120396 0.3048)
			(end 0.120396 0.2794)
			(stroke
				(width 0.1)
				(type default)
			)
			(layer "F.Fab")
		)
		(fp_line
			(start -0.12065 0.3048)
			(end -0.67945 0.3048)
			(stroke
				(width 0.1)
				(type default)
			)
			(layer "F.Fab")
		)
		(fp_line
			(start -0.67945 0.3048)
			(end -0.67945 -0.305054)
			(stroke
				(width 0.1)
				(type default)
			)
			(layer "F.Fab")
		)
		(pad "1" smd circle
			(at -0.40005 0 90)
			(size 0 0)
			(layers "F.Cu" "F.Mask" "F.Paste")
			(net "FM_AC_PWR_BTN_PDB_N")
		)
		(pad "2" smd circle
			(at 0.40005 0 90)
			(size 0 0)
			(layers "F.Cu" "F.Mask" "F.Paste")
			(net "GND")
		)
	)
	(footprint ""
		(layer "F.Cu")
		(at 276.520402 -76.110084 180)
		(property "Reference" ""
			(at 0 0 180)
			(layer "F.SilkS")
			(hide yes)
			(effects
				(font
					(size 1.27 1.27)
				)
			)
		)
		(property "Value" ""
			(at 0 0 180)
			(layer "F.Fab")
			(effects
				(font
					(size 1.27 1.27)
				)
			)
		)
		(duplicate_pad_numbers_are_jumpers no)
		(pad "1" smd circle
			(at 0 0 180)
			(size 0.9906 0.9906)
			(layers "F.Cu" "F.Mask" "F.Paste")
			(net "Net_44")
		)
		(zone
			(layer "F.Cu")
			(hatch none 0.5)
			(connect_pads
				(clearance 0)
			)
			(min_thickness 0.25)
			(keepout
				(tracks not_allowed)
				(vias allowed)
				(pads allowed)
				(copperpour not_allowed)
				(footprints allowed)
			)
			(placement
				(enabled no)
				(sheetname "")
			)
			(fill
				(thermal_gap 0.5)
				(thermal_bridge_width 0.5)
				(island_removal_mode 0)
			)
			(polygon
				(pts
					(arc
						(start 278.146002 -76.110084)
						(mid 274.894802 -76.110084)
						(end 278.146002 -76.110084)
					)
				)
			)
		)
	)
)
